# T6G (Grand Teton) — schematic parts with pin connectivity, parts 3030–3178 of 8303; source: Cadence DE-HDL packaged netlist (pstxprt.dat, pstxnet.dat, pstchip.dat)

PC257  Q_CAP  2.2UF 10V 10% X6S  pkg C0402  page 211 : 1 = PVDDCR_CPU0_P1_VCC2 ; 2 = GND
PC258  Q_CAP  0.022UF 25V 10% X7R  pkg 0402  page 209 : 1 = PVDD18_S5_P0_REF ; 2 = GND
PC258_C0P1_1  Q_CAP  2.2UF 10V 10% X6S  pkg C0402  page 211 : 1 = PVDDCR_CPU0_P1_PVCC ; 2 = GND
PC259  Q_CAP  220PF 50V 10% X7R  pkg 0402  page 209 : 1 = PVDD18_S5_P0_FB ; 2 = PVDD18_S5_P0_FB_RC
PC259_C0P1_2  Q_CAP  2.2UF 10V 10% X6S  pkg C0402  page 211 : 1 = PVDDCR_CPU0_P1_PVCC ; 2 = GND
PC260  Q_CAP  22UF 4V 20% EMPTY  pkg C0805  page 209 : 1 = PVDD18_S5_P0 ; 2 = GND
PC260_1  Q_CAP  0.1UF 25V 10% X7R  pkg 0402  page 211 : 1 = SW_P12V_AUX_PVDDCR_CPU0_P1_FLT ; 2 = GND
PC261  Q_CAP  22UF 4V 20% EMPTY  pkg C0805  page 209 : 1 = PVDD18_S5_P0 ; 2 = GND
PC261_2  Q_CAP  0.1UF 25V 10% X7R  pkg 0402  page 211 : 1 = SW_P12V_AUX_PVDDCR_CPU0_P1_FLT ; 2 = GND
PC262_1  Q_CAP  1UF 25V 10% X6S  pkg C0402  page 211 : 1 = SW_P12V_AUX_PVDDCR_CPU0_P1_FLT ; 2 = GND
PC263_2  Q_CAP  1UF 25V 10% X6S  pkg C0402  page 211 : 1 = SW_P12V_AUX_PVDDCR_CPU0_P1_FLT ; 2 = GND
PC264_1  Q_CAP  22UF 16V 20% X6S  pkg C0805  page 211 : 1 = SW_P12V_AUX_PVDDCR_CPU0_P1_FLT ; 2 = GND
PC265_2  Q_CAP  22UF 16V 20% X6S  pkg C0805  page 211 : 1 = SW_P12V_AUX_PVDDCR_CPU0_P1_FLT ; 2 = GND
PC266_1  Q_CAP  22UF 16V 20% X6S  pkg C0805  page 211 : 1 = SW_P12V_AUX_PVDDCR_CPU0_P1_FLT ; 2 = GND
PC267_2  Q_CAP  22UF 16V 20% X6S  pkg C0805  page 211 : 1 = SW_P12V_AUX_PVDDCR_CPU0_P1_FLT ; 2 = GND
PC268_1  Q_CAP  22UF 16V 20% X6S  pkg C0805  page 211 : 1 = SW_P12V_AUX_PVDDCR_CPU0_P1_FLT ; 2 = GND
PC269_2  Q_CAP  22UF 16V 20% X6S  pkg C0805  page 211 : 1 = SW_P12V_AUX_PVDDCR_CPU0_P1_FLT ; 2 = GND
PC270  Q_CAP  0.22UF 16V 10% X7R  pkg 0402  page 211 : 1 = SW_PVDDCR_CPU0_P1_BOOT1_RC ; 2 = SW_PVDDCR_CPU0_P1_PH1
PC271  Q_CAP  0.22UF 16V 10% X7R  pkg 0402  page 211 : 1 = SW_PVDDCR_CPU0_P1_BOOT2_RC ; 2 = SW_PVDDCR_CPU0_P1_PH2
PC272  Q_CAPP  270UF 16V 20% OSCON  pkg THLF  page 211 : 1 = SW_P12V_AUX_PVDDCR_CPU0_P1_FLT ; 2 = GND
PC273  Q_CAPP  270UF 16V 20% OSCON  pkg THLF  page 211 : 1 = SW_P12V_AUX_PVDDCR_CPU0_P1_FLT ; 2 = GND
PC275  Q_CAPP  220UF 4V 20% SPCAP  pkg SMLF  page 211 : 1 = PVDDCR_CPU0_P1 ; 2 = GND
PC276  Q_CAPP  220UF 4V 20% SPCAP  pkg SMLF  page 211 : 1 = PVDDCR_CPU0_P1 ; 2 = GND
PC277  Q_CAPP  220UF 4V 20% SPCAP  pkg SMLF  page 211 : 1 = PVDDCR_CPU0_P1 ; 2 = GND
PC278  Q_CAP  0.1UF 25V 10% X7R  pkg 0402  page 211 : 1 = PVDDCR_CPU0_P1 ; 2 = GND
PC279  Q_CAPP  220UF 4V 20% SPCAP  pkg SMLF  page 211 : 1 = PVDDCR_CPU0_P1 ; 2 = GND
PC280_2  Q_CAP  22UF 4V 20% X6S  pkg C0805  page 211 : 1 = PVDDCR_CPU0_P1 ; 2 = GND
PC281_1  Q_CAP  22UF 4V 20% X6S  pkg C0805  page 211 : 1 = PVDDCR_CPU0_P1 ; 2 = GND
PC282_2  Q_CAP  22UF 4V 20% X6S  pkg C0805  page 211 : 1 = PVDDCR_CPU0_P1 ; 2 = GND
PC283_1  Q_CAP  22UF 4V 20% X6S  pkg C0805  page 211 : 1 = PVDDCR_CPU0_P1 ; 2 = GND
PC284_3  Q_CAP  0.1UF 25V 10% X7R  pkg 0402  page 212 : 1 = PVDDCR_CPU0_P1_VCCS ; 2 = GND
PC285  Q_CAP  22UF 4V 20% X6S  pkg C0805  page 209 : 1 = PVDD18_S5_P0 ; 2 = GND
PC285_4  Q_CAP  0.1UF 25V 10% X7R  pkg 0402  page 212 : 1 = PVDDCR_CPU0_P1_VCCS ; 2 = GND
PC286  Q_CAP  2.2UF 10V 10% X6S  pkg C0402  page 212 : 1 = PVDDCR_CPU0_P1_VCC3 ; 2 = GND
PC287  Q_CAP  2.2UF 10V 10% X6S  pkg C0402  page 212 : 1 = PVDDCR_CPU0_P1_VCC4 ; 2 = GND
PC288  Q_CAP  22UF 4V 20% X6S  pkg C0805  page 209 : 1 = PVDD18_S5_P0 ; 2 = GND
PC288_C0P1_3  Q_CAP  2.2UF 10V 10% X6S  pkg C0402  page 212 : 1 = PVDDCR_CPU0_P1_PVCC ; 2 = GND
PC289_C0P1_4  Q_CAP  2.2UF 10V 10% X6S  pkg C0402  page 212 : 1 = PVDDCR_CPU0_P1_PVCC ; 2 = GND
PC290_3  Q_CAP  0.1UF 25V 10% X7R  pkg 0402  page 212 : 1 = SW_P12V_AUX_PVDDCR_CPU0_P1_FLT ; 2 = GND
PC291_4  Q_CAP  1UF 25V 10% X6S  pkg C0402  page 212 : 1 = SW_P12V_AUX_PVDDCR_CPU0_P1_FLT ; 2 = GND
PC292_3  Q_CAP  1UF 25V 10% X6S  pkg C0402  page 212 : 1 = SW_P12V_AUX_PVDDCR_CPU0_P1_FLT ; 2 = GND
PC293_4  Q_CAP  0.1UF 25V 10% X7R  pkg 0402  page 212 : 1 = SW_P12V_AUX_PVDDCR_CPU0_P1_FLT ; 2 = GND
PC294_3  Q_CAP  22UF 16V 20% X6S  pkg C0805  page 212 : 1 = SW_P12V_AUX_PVDDCR_CPU0_P1_FLT ; 2 = GND
PC295_4  Q_CAP  22UF 16V 20% X6S  pkg C0805  page 212 : 1 = SW_P12V_AUX_PVDDCR_CPU0_P1_FLT ; 2 = GND
PC296_3  Q_CAP  22UF 16V 20% X6S  pkg C0805  page 212 : 1 = SW_P12V_AUX_PVDDCR_CPU0_P1_FLT ; 2 = GND
PC297_4  Q_CAP  22UF 16V 20% X6S  pkg C0805  page 212 : 1 = SW_P12V_AUX_PVDDCR_CPU0_P1_FLT ; 2 = GND
PC298_3  Q_CAP  22UF 16V 20% X6S  pkg C0805  page 212 : 1 = SW_P12V_AUX_PVDDCR_CPU0_P1_FLT ; 2 = GND
PC299_4  Q_CAP  22UF 16V 20% X6S  pkg C0805  page 212 : 1 = SW_P12V_AUX_PVDDCR_CPU0_P1_FLT ; 2 = GND
PC300  Q_CAP  0.22UF 16V 10% X7R  pkg 0402  page 212 : 1 = SW_PVDDCR_CPU0_P1_BOOT3_RC ; 2 = SW_PVDDCR_CPU0_P1_PH3
PC301  Q_CAP  0.22UF 16V 10% X7R  pkg 0402  page 212 : 1 = SW_PVDDCR_CPU0_P1_BOOT4_RC ; 2 = SW_PVDDCR_CPU0_P1_PH4
PC302_3  Q_CAP  22UF 4V 20% X6S  pkg C0805  page 212 : 1 = PVDDCR_CPU0_P1 ; 2 = GND
PC303_4  Q_CAP  22UF 4V 20% X6S  pkg C0805  page 212 : 1 = PVDDCR_CPU0_P1 ; 2 = GND
PC304_3  Q_CAP  22UF 4V 20% X6S  pkg C0805  page 212 : 1 = PVDDCR_CPU0_P1 ; 2 = GND
PC305_4  Q_CAP  22UF 4V 20% X6S  pkg C0805  page 212 : 1 = PVDDCR_CPU0_P1 ; 2 = GND
PC306_5  Q_CAP  0.1UF 25V 10% X7R  pkg 0402  page 213 : 1 = PVDDCR_CPU0_P1_VCCS ; 2 = GND
PC307  Q_CAP  2.2UF 10V 10% X6S  pkg C0402  page 213 : 1 = PVDDCR_CPU0_P1_VCC5 ; 2 = GND
PC308_C0P1_5  Q_CAP  2.2UF 10V 10% X6S  pkg C0402  page 213 : 1 = PVDDCR_CPU0_P1_PVCC ; 2 = GND
PC309_5  Q_CAP  0.1UF 25V 10% X7R  pkg 0402  page 213 : 1 = SW_P12V_AUX_PVDDCR_CPU0_P1_FLT ; 2 = GND
PC310_5  Q_CAP  1UF 25V 10% X6S  pkg C0402  page 213 : 1 = SW_P12V_AUX_PVDDCR_CPU0_P1_FLT ; 2 = GND
PC311_5  Q_CAP  22UF 16V 20% X6S  pkg C0805  page 213 : 1 = SW_P12V_AUX_PVDDCR_CPU0_P1_FLT ; 2 = GND
PC312_5  Q_CAP  22UF 16V 20% X6S  pkg C0805  page 213 : 1 = SW_P12V_AUX_PVDDCR_CPU0_P1_FLT ; 2 = GND
PC313_5  Q_CAP  22UF 16V 20% X6S  pkg C0805  page 213 : 1 = SW_P12V_AUX_PVDDCR_CPU0_P1_FLT ; 2 = GND
PC314  Q_CAP  0.22UF 16V 10% X7R  pkg 0402  page 213 : 1 = SW_PVDDCR_CPU0_P1_BOOT5_RC ; 2 = SW_PVDDCR_CPU0_P1_PH5
PC315  Q_CAP  560PF 50V 10% EMPTY  pkg C0402  page 225 : 1 = SW_PVDD11_S3_P1_SW1 ; 2 = SW_PVDD11_S3_P1_SW1_RC
PC315_5  Q_CAP  22UF 4V 20% X6S  pkg C0805  page 213 : 1 = PVDDCR_CPU0_P1 ; 2 = GND
PC316  Q_CAP  560PF 50V 10% EMPTY  pkg C0402  page 212 : 1 = SW_PVDDCR_CPU0_P1_SW3 ; 2 = SW_PVDDCR_CPU0_P1_SW3_RC
PC316_5  Q_CAP  22UF 4V 20% X6S  pkg C0805  page 213 : 1 = PVDDCR_CPU0_P1 ; 2 = GND
PC317  Q_CAP  560PF 50V 10% EMPTY  pkg C0402  page 212 : 1 = SW_PVDDCR_CPU0_P1_SW4 ; 2 = SW_PVDDCR_CPU0_P1_SW4_RC
PC317_7  Q_CAP  0.1UF 25V 10% X7R  pkg 0402  page 215 : 1 = PVDDCR_CPU0_P1_VCCS ; 2 = GND
PC318  Q_CAP  560PF 50V 10% EMPTY  pkg C0402  page 213 : 1 = SW_PVDDCR_CPU0_P1_SW5 ; 2 = SW_PVDDCR_CPU0_P1_SW5_RC
PC318_8  Q_CAP  0.1UF 25V 10% X7R  pkg 0402  page 215 : 1 = PVDDCR_CPU0_P1_VCCS ; 2 = GND
PC319  Q_CAP  2.2UF 10V 10% X6S  pkg C0402  page 215 : 1 = PVDDCR_SOC_P1_VCC1 ; 2 = GND
PC320  Q_CAP  2.2UF 10V 10% X6S  pkg C0402  page 215 : 1 = PVDDCR_SOC_P1_VCC2 ; 2 = GND
PC321  Q_CAP  560PF 50V 10% EMPTY  pkg C0402  page 213 : 1 = SW_PVDDCR_CPU0_P1_SW6 ; 2 = SW_PVDDCR_CPU0_P1_SW6_RC
PC321_SOP1_1  Q_CAP  2.2UF 10V 10% X6S  pkg C0402  page 215 : 1 = PVDDCR_CPU0_P1_PVCC ; 2 = GND
PC322_SOP1_2  Q_CAP  2.2UF 10V 10% X6S  pkg C0402  page 215 : 1 = PVDDCR_CPU0_P1_PVCC ; 2 = GND
PC323_1  Q_CAP  1UF 25V 10% X6S  pkg C0402  page 215 : 1 = SW_P12V_AUX_PVDDCR_SOC_P1_FLT ; 2 = GND
PC324_2  Q_CAP  1UF 25V 10% X6S  pkg C0402  page 215 : 1 = SW_P12V_AUX_PVDDCR_SOC_P1_FLT ; 2 = GND
PC325_1  Q_CAP  0.1UF 25V 10% X7R  pkg 0402  page 215 : 1 = SW_P12V_AUX_PVDDCR_SOC_P1_FLT ; 2 = GND
PC326_2  Q_CAP  0.1UF 25V 10% X7R  pkg 0402  page 215 : 1 = SW_P12V_AUX_PVDDCR_SOC_P1_FLT ; 2 = GND
PC327_1  Q_CAP  22UF 16V 20% X6S  pkg C0805  page 215 : 1 = SW_P12V_AUX_PVDDCR_SOC_P1_FLT ; 2 = GND
PC328_2  Q_CAP  22UF 16V 20% X6S  pkg C0805  page 215 : 1 = SW_P12V_AUX_PVDDCR_SOC_P1_FLT ; 2 = GND
PC329_1  Q_CAP  22UF 16V 20% X6S  pkg C0805  page 215 : 1 = SW_P12V_AUX_PVDDCR_SOC_P1_FLT ; 2 = GND
PC330_2  Q_CAP  22UF 16V 20% X6S  pkg C0805  page 215 : 1 = SW_P12V_AUX_PVDDCR_SOC_P1_FLT ; 2 = GND
PC331_1  Q_CAP  22UF 16V 20% X6S  pkg C0805  page 215 : 1 = SW_P12V_AUX_PVDDCR_SOC_P1_FLT ; 2 = GND
PC332_2  Q_CAP  22UF 16V 20% X6S  pkg C0805  page 215 : 1 = SW_P12V_AUX_PVDDCR_SOC_P1_FLT ; 2 = GND
PC333  Q_CAP  0.22UF 16V 10% X7R  pkg 0402  page 215 : 1 = SW_PVDDCR_SOC_P1_BOOT1_RC ; 2 = SW_PVDDCR_SOC_P1_PH1
PC334  Q_CAP  0.22UF 16V 10% X7R  pkg 0402  page 215 : 1 = SW_PVDDCR_SOC_P1_BOOT2_RC ; 2 = SW_PVDDCR_SOC_P1_PH2
PC334_1  Q_CAP  22UF 16V 20% X6S  pkg C0805  page 215 : 1 = SW_P12V_AUX_PVDDCR_SOC_P1_FLT ; 2 = GND
PC335_2  Q_CAP  22UF 16V 20% X6S  pkg C0805  page 215 : 1 = SW_P12V_AUX_PVDDCR_SOC_P1_FLT ; 2 = GND
PC336  Q_CAPP  270UF 16V 20% OSCON  pkg THLF  page 215 : 1 = SW_P12V_AUX_PVDDCR_SOC_P1_FLT ; 2 = GND
PC337  Q_CAPP  470UF 2.5V 20% SPCAP  pkg SMLF  page 215 : 1 = PVDDCR_SOC_P1 ; 2 = GND
PC338  Q_CAP  0.1UF 25V 10% X7R  pkg 0402  page 215 : 1 = PVDDCR_SOC_P1 ; 2 = GND
PC339_2  Q_CAP  22UF 4V 20% X6S  pkg C0805  page 215 : 1 = PVDDCR_SOC_P1 ; 2 = GND
PC340  Q_CAPP  470UF 2.5V 20% EMPTY  pkg SMLF  page 215 : 1 = PVDDCR_SOC_P1 ; 2 = GND
PC341_1  Q_CAP  22UF 4V 20% X6S  pkg C0805  page 215 : 1 = PVDDCR_SOC_P1 ; 2 = GND
PC342_2  Q_CAP  22UF 4V 20% X6S  pkg C0805  page 215 : 1 = PVDDCR_SOC_P1 ; 2 = GND
PC343  Q_CAPP  470UF 2.5V 20% SPCAP  pkg SMLF  page 215 : 1 = PVDDCR_SOC_P1 ; 2 = GND
PC344_1  Q_CAP  22UF 4V 20% X6S  pkg C0805  page 215 : 1 = PVDDCR_SOC_P1 ; 2 = GND
PC345_9  Q_CAP  0.1UF 25V 10% X7R  pkg 0402  page 216 : 1 = PVDDCR_CPU0_P1_VCCS ; 2 = GND
PC346  Q_CAP  2.2UF 10V 10% X6S  pkg C0402  page 216 : 1 = PVDDCR_SOC_P1_VCC3 ; 2 = GND
PC347_SOP1_3  Q_CAP  2.2UF 10V 10% X6S  pkg C0402  page 216 : 1 = PVDDCR_CPU0_P1_PVCC ; 2 = GND
PC348_3  Q_CAP  0.1UF 25V 10% X7R  pkg 0402  page 216 : 1 = SW_P12V_AUX_PVDDCR_SOC_P1_FLT ; 2 = GND
PC349_3  Q_CAP  1UF 25V 10% X6S  pkg C0402  page 216 : 1 = SW_P12V_AUX_PVDDCR_SOC_P1_FLT ; 2 = GND
PC350_3  Q_CAP  22UF 16V 20% X6S  pkg C0805  page 216 : 1 = SW_P12V_AUX_PVDDCR_SOC_P1_FLT ; 2 = GND
PC351_3  Q_CAP  22UF 16V 20% X6S  pkg C0805  page 216 : 1 = SW_P12V_AUX_PVDDCR_SOC_P1_FLT ; 2 = GND
PC352_3  Q_CAP  22UF 16V 20% X6S  pkg C0805  page 216 : 1 = SW_P12V_AUX_PVDDCR_SOC_P1_FLT ; 2 = GND
PC353  Q_CAP  0.22UF 16V 10% X7R  pkg 0402  page 216 : 1 = SW_PVDDCR_SOC_P1_BOOT3_RC ; 2 = SW_PVDDCR_SOC_P1_PH3
PC353_3  Q_CAP  22UF 16V 20% X6S  pkg C0805  page 216 : 1 = SW_P12V_AUX_PVDDCR_SOC_P1_FLT ; 2 = GND
PC354_3  Q_CAP  22UF 4V 20% X6S  pkg C0805  page 216 : 1 = PVDDCR_SOC_P1 ; 2 = GND
PC355_3  Q_CAP  22UF 4V 20% X6S  pkg C0805  page 216 : 1 = PVDDCR_SOC_P1 ; 2 = GND
PC357  Q_CAP  0.1UF 25V 10% X7R  pkg 0402  page 217 : 1 = PVDDCR_CPU1_P1_VMON ; 2 = GND
PC358  Q_CAP  3300PF 50V 10% X7R  pkg 0402  page 217 : 1 = VSENSE_PVDDCR_CPU1_P1_VSEN0 ; 2 = VSENSE_VSS_SENSE_C_P1
PC361  Q_CAP  3300PF 50V 10% X7R  pkg 0402  page 217 : 1 = VSENSE_PVDDIO_P1_VSEN1 ; 2 = VSENSE_VSS_SENSE_B_P1
PC363  Q_CAP  1UF 6.3V 10% X7R  pkg 0402  page 217 : 1 = PVDD18_S5_P1 ; 2 = GND
PC364  Q_CAP  0.1UF 25V 10% X7R  pkg 0402  page 217 : 1 = PVDDCR_CPU1_P1_VINSEN ; 2 = GND
PC365  Q_CAP  1UF 16V 10% X6S  pkg C0402  page 217 : 1 = PVDDCR_CPU1_P1_VCC ; 2 = GND
PC366  Q_CAP  10UF 6.3V 20% X6S  pkg C0402  page 217 : 1 = PVDDCR_CPU1_P1_VCCS ; 2 = GND
PC367  Q_CAP  470PF 50V 10% X7R  pkg 0402  page 217 : 1 = PVDDIO_P1_TEMP1 ; 2 = GND
PC368  Q_CAP  470PF 50V 10% X7R  pkg 0402  page 217 : 1 = PVDDCR_CPU1_P1_TEMP0 ; 2 = GND
PC369  Q_CAP  2.2UF 10V 10% X6S  pkg C0402  page 218 : 1 = PVDDCR_CPU1_P1_VCC1 ; 2 = GND
PC370  Q_CAP  2.2UF 10V 10% X6S  pkg C0402  page 218 : 1 = PVDDCR_CPU1_P1_VCC2 ; 2 = GND
PC371_C1P1_1  Q_CAP  2.2UF 10V 10% X6S  pkg C0402  page 218 : 1 = PVDDCR_CPU1_P1_PVCC ; 2 = GND
PC372_C1P1_2  Q_CAP  2.2UF 10V 10% X6S  pkg C0402  page 218 : 1 = PVDDCR_CPU1_P1_PVCC ; 2 = GND
PC373_2  Q_CAP  0.1UF 25V 10% X7R  pkg 0402  page 218 : 1 = PVDDCR_CPU1_P1_VCCS ; 2 = GND
PC374_1  Q_CAP  0.1UF 25V 10% X7R  pkg 0402  page 218 : 1 = PVDDCR_CPU1_P1_VCCS ; 2 = GND
PC375  Q_CAP  0.1UF 25V 10% X7R  pkg 0402  page 218 : 1 = P12V_AUX ; 2 = GND
PC375_1  Q_CAP  0.1UF 25V 10% X7R  pkg 0402  page 218 : 1 = SW_P12V_AUX_PVDDCR_CPU1_P1_FLT ; 2 = GND
PC376_2  Q_CAP  0.1UF 25V 10% X7R  pkg 0402  page 218 : 1 = SW_P12V_AUX_PVDDCR_CPU1_P1_FLT ; 2 = GND
PC377_1  Q_CAP  1UF 25V 10% X6S  pkg C0402  page 218 : 1 = SW_P12V_AUX_PVDDCR_CPU1_P1_FLT ; 2 = GND
PC378_2  Q_CAP  1UF 25V 10% X6S  pkg C0402  page 218 : 1 = SW_P12V_AUX_PVDDCR_CPU1_P1_FLT ; 2 = GND
PC379_1  Q_CAP  22UF 16V 20% X6S  pkg C0805  page 218 : 1 = SW_P12V_AUX_PVDDCR_CPU1_P1_FLT ; 2 = GND
PC380_2  Q_CAP  22UF 16V 20% X6S  pkg C0805  page 218 : 1 = SW_P12V_AUX_PVDDCR_CPU1_P1_FLT ; 2 = GND
PC381_1  Q_CAP  22UF 16V 20% X6S  pkg C0805  page 218 : 1 = SW_P12V_AUX_PVDDCR_CPU1_P1_FLT ; 2 = GND
PC382_2  Q_CAP  22UF 16V 20% X6S  pkg C0805  page 218 : 1 = SW_P12V_AUX_PVDDCR_CPU1_P1_FLT ; 2 = GND
PC383  Q_CAP  0.22UF 16V 10% X7R  pkg 0402  page 218 : 1 = SW_PVDDCR_CPU1_P1_BOOT1_R ; 2 = SW_PVDDCR_CPU1_P1_BOOTR1
PC384  Q_CAP  3300PF 50V 10% X7R  pkg 0402  page 269 : 1 = P1V8_AUX_REF ; 2 = GND
PC384_1  Q_CAP  22UF 16V 20% X6S  pkg C0805  page 218 : 1 = SW_P12V_AUX_PVDDCR_CPU1_P1_FLT ; 2 = GND
PC385_2  Q_CAP  22UF 16V 20% X6S  pkg C0805  page 218 : 1 = SW_P12V_AUX_PVDDCR_CPU1_P1_FLT ; 2 = GND
PC386  Q_CAP  0.22UF 16V 10% X7R  pkg 0402  page 218 : 1 = SW_PVDDCR_CPU1_P1_BOOT2_R ; 2 = SW_PVDDCR_CPU1_P1_BOOTR2
PC387  Q_CAPP  220UF 4V 20% SPCAP  pkg SMLF  page 218 : 1 = PVDDCR_CPU1_P1 ; 2 = GND
PC388  Q_CAPP  220UF 4V 20% SPCAP  pkg SMLF  page 218 : 1 = PVDDCR_CPU1_P1 ; 2 = GND
PC389  Q_CAPP  220UF 4V 20% SPCAP  pkg SMLF  page 218 : 1 = PVDDCR_CPU1_P1 ; 2 = GND
PC390  Q_CAPP  270UF 16V 20% OSCON  pkg SMLF  page 218 : 1 = SW_P12V_AUX_PVDDCR_CPU1_P1_FLT ; 2 = GND
PC391  Q_CAPP  220UF 4V 20% SPCAP  pkg SMLF  page 218 : 1 = PVDDCR_CPU1_P1 ; 2 = GND
PC392  Q_CAP  0.1UF 25V 10% X7R  pkg 0402  page 218 : 1 = PVDDCR_CPU1_P1 ; 2 = GND
PC393  Q_CAPP  270UF 16V 20% OSCON  pkg SMLF  page 218 : 1 = SW_P12V_AUX_PVDDCR_CPU1_P1_FLT ; 2 = GND
PC394_2  Q_CAP  22UF 4V 20% X6S  pkg C0805  page 218 : 1 = PVDDCR_CPU1_P1 ; 2 = GND
PC395_1  Q_CAP  22UF 4V 20% X6S  pkg C0805  page 218 : 1 = PVDDCR_CPU1_P1 ; 2 = GND
